FILE_TYPE = CONNECTIVITY;
{Allegro Design Entry HDL 17.2-2016 S081 (4005846) 1/11/2022}
"PAGE_NUMBER" = 26;
0"NC";
1"P3V3_AUX\g";
2"P3V3_AUX\g";
3"P3V3_AUX\g";
4"P3V3_AUX\g";
5"GND\g";
6"GND\g";
7"GND\g";
8"GND\g";
9"GND\g";
10"GND\g";
11"GND\g";
12"TMC75_A2";
13"SMB_BMC_ALERT16_R_N";
14"SMB_TMP421_BMC_MM2_SCL";
15"SMB_TMP421_BMC_MM2_SDA";
16"FRU_E0";
17"FRU_E1";
18"FRU_E2";
19"SMB_BMC_MM16_R2_SDA";
20"PD_FRU_WC_N";
21"SMB_BMC_MM16_SDA";
22"SMB_BMC_MM16_R2_SCL";
23"SMB_BMC_MM16_SCL";
24"TMC75_A1";
25"SMB_BMC_ALERT16_N";
26"SMB_BMC_MM2_SCL";
27"SMB_BMC_MM2_SDA";
28"TMC75_A0";
%"UNIVERSAL_POWER"
"1","(-1800,1650)","0","logical_power","I10";
;
HDL_POWER"P3V3_AUX"
CDS_LIB"logical_power";
"A"3;
%"Q_RES"
"2","(-1450,1175)","0","pure_quanta","I11";
;
VALUE"4.7K"
TOLERANCE"1%"
PACK_TYPE"0402LF"
WATTAGE"1/16W"
MATERIAL"EMPTY"
CDS_LIB"pure_quanta"
SEC_TYPE"0402LF"
PART_NUMBER"CS24702FB06"
LOCATION"R13"
SEC"1";
"A"
$PN"1"3;
"B"
$PN"2"17;
%"Q_RES"
"2","(-1100,500)","0","pure_quanta","I12";
;
WATTAGE"1/16W"
TOLERANCE"1%"
VALUE"100"
PACK_TYPE"0402LF"
PART_NUMBER"CS11002FB07"
MATERIAL"CHIP"
CDS_LIB"pure_quanta"
LOCATION"R413"
$SEC"1"
CDS_SEC"1";
"A"
$PN"1"18;
"B"
$PN"2"8;
%"UNIVERSAL_GND"
"1","(-175,550)","0","logical_power","I13";
;
CDS_LIB"logical_power"
HDL_POWER"GND";
"A"6;
%"Q_RES"
"2","(-1100,1175)","0","pure_quanta","I14";
;
MATERIAL"EMPTY"
PART_NUMBER"CS24702FB06"
PACK_TYPE"0402LF"
TOLERANCE"1%"
WATTAGE"1/16W"
VALUE"4.7K"
CDS_LIB"pure_quanta"
SEC_TYPE"0402LF"
LOCATION"R14"
SEC"1";
"A"
$PN"1"3;
"B"
$PN"2"18;
%"M24128BWDW6TP"
"1","(225,775)","0","pure_quanta","I15";
;
PART_TYPE"SMLF"
VALUE"M24128-BWDW6TP"
PART_NUMBER"AKE30Z0K610"
MATERIAL"IC"
CDS_LIB"pure_quanta"
CDS_LMAN_SYM_OUTLINE"-150,125,150,-125"
NEEDS_NO_SIZE"TRUE"
LOCATION"U19"
$SEC"1"
CDS_SEC"1";
"E0"
$PN"1"16;
"E1"
$PN"2"17;
"E2"
$PN"3"18;
"VSS"
$PN"4"6;
"SDA"
$PN"5"19;
"SCL"
$PN"6"22;
"WC# \B"
$PN"7"20;
"VCC"
$PN"8"2;
%"UNIVERSAL_GND"
"1","(875,900)","0","logical_power","I16";
;
CDS_LIB"logical_power"
HDL_POWER"GND";
"A"7;
%"Q_CAP"
"1","(875,1150)","0","pure_quanta","I17";
;
VALUE"0.1UF"
VOLTAGE"25V"
TOLERANCE"10%"
MATERIAL"X7R"
PACK_TYPE"0402"
PART_NUMBER"CH4104K1B00"
CDS_LIB"pure_quanta"
LOCATION"C192"
$SEC"1"
CDS_SEC"1";
"B"
$PN"2"7;
"A"
$PN"1"2;
%"UNIVERSAL_POWER"
"1","(675,1500)","0","logical_power","I18";
;
HDL_POWER"P3V3_AUX"
CDS_LIB"logical_power";
"A"2;
%"UNIVERSAL_GND"
"1","(1075,175)","0","logical_power","I31";
;
HDL_POWER"GND"
CDS_LIB"logical_power";
"A"9;
%"Q_RES"
"2","(1075,450)","0","pure_quanta","I32";
;
WATTAGE"1/16W"
TOLERANCE"1%"
PART_NUMBER"CS21002FB06"
PACK_TYPE"0402LF"
VALUE"1K"
MATERIAL"CHIP"
CDS_LIB"pure_quanta"
LOCATION"R15"
$SEC"1"
CDS_SEC"1";
"A"
$PN"1"20;
"B"
$PN"2"9;
%"Q_RES"
"1","(2275,700)","0","pure_quanta","I33";
;
MATERIAL"CHIP"
VALUE"33.2"
CDS_LIB"pure_quanta"
WATTAGE"1/16W"
PACK_TYPE"0402LF"
PART_NUMBER"CS03322FB03"
TOLERANCE"1%"
LOCATION"R421"
$SEC"1"
CDS_SEC"1";
"B"
$PN"2"21;
"A"
$PN"1"19;
%"Q_RES"
"2","(-1725,2650)","0","pure_quanta","I37";
;
WATTAGE"1/16W"
PACK_TYPE"0402LF"
MATERIAL"CHIP"
TOLERANCE"1%"
VALUE"1K"
SEC_TYPE"0402LF"
CDS_LIB"pure_quanta"
PART_NUMBER"CS21002FB06"
LOCATION"R419"
SEC"1";
"A"
$PN"1"12;
"B"
$PN"2"11;
%"UNIVERSAL_GND"
"1","(-1275,2325)","0","logical_power","I38";
;
CDS_LIB"logical_power"
HDL_POWER"GND";
"A"11;
%"Q_RES"
"2","(-1175,2650)","0","pure_quanta","I39";
;
MATERIAL"EMPTY"
PACK_TYPE"0402LF"
WATTAGE"1/16W"
TOLERANCE"1%"
VALUE"1K"
PART_NUMBER"CS21002FB06"
CDS_LIB"pure_quanta"
SEC_TYPE"0402LF"
LOCATION"R417"
SEC"1";
"A"
$PN"1"28;
"B"
$PN"2"11;
%"Q_RES"
"2","(-1725,3350)","0","pure_quanta","I40";
;
MATERIAL"EMPTY"
PACK_TYPE"0402LF"
TOLERANCE"1%"
VALUE"4.7K"
WATTAGE"1/16W"
PART_NUMBER"CS24702FB06"
CDS_LIB"pure_quanta"
LOCATION"R418"
$SEC"1"
CDS_SEC"1";
"A"
$PN"1"1;
"B"
$PN"2"12;
%"Q_RES"
"2","(-1175,3350)","0","pure_quanta","I41";
;
TOLERANCE"1%"
MATERIAL"CHIP"
PACK_TYPE"0402LF"
WATTAGE"1/16W"
VALUE"4.7K"
PART_NUMBER"CS24702FB06"
CDS_LIB"pure_quanta"
LOCATION"R416"
$SEC"1"
CDS_SEC"1";
"A"
$PN"1"1;
"B"
$PN"2"28;
%"UNIVERSAL_GND"
"1","(525,2700)","0","logical_power","I52";
;
HDL_POWER"GND"
CDS_LIB"logical_power";
"A"5;
%"UNIVERSAL_POWER"
"1","(-325,4050)","0","logical_power","I53";
;
HDL_POWER"P3V3_AUX"
CDS_LIB"logical_power";
"A"4;
%"Q_CAP"
"1","(-125,3775)","0","pure_quanta","I54";
;
VOLTAGE"25V"
VALUE"0.1UF"
TOLERANCE"10%"
MATERIAL"X7R"
PACK_TYPE"0402"
PART_NUMBER"CH4104K1B00"
CDS_LIB"pure_quanta"
LOCATION"C191"
$SEC"1"
CDS_SEC"1";
"B"
$PN"2"10;
"A"
$PN"1"4;
%"UNIVERSAL_GND"
"1","(-125,3550)","0","logical_power","I55";
;
CDS_LIB"logical_power"
HDL_POWER"GND";
"A"10;
%"Q_RES"
"1","(1625,3025)","0","pure_quanta","I56";
;
MATERIAL"CHIP"
VALUE"49.9"
CDS_LIB"pure_quanta"
WATTAGE"1/16W"
PACK_TYPE"0402LF"
PART_NUMBER"CS04992FB07"
TOLERANCE"1%"
LOCATION"R410"
$SEC"1"
CDS_SEC"1";
"B"
$PN"2"26;
"A"
$PN"1"14;
%"Q_RES"
"1","(1625,3125)","0","pure_quanta","I57";
;
MATERIAL"CHIP"
VALUE"49.9"
PART_NUMBER"CS04992FB07"
PACK_TYPE"0402LF"
WATTAGE"1/16W"
CDS_LIB"pure_quanta"
TOLERANCE"1%"
LOCATION"R409"
$SEC"1"
CDS_SEC"1";
"B"
$PN"2"27;
"A"
$PN"1"15;
%"UNIVERSAL_POWER"
"1","(-1175,3725)","0","logical_power","I58";
;
HDL_POWER"P3V3_AUX"
CDS_LIB"logical_power";
"A"1;
%"Q_RES"
"2","(-1800,500)","0","pure_quanta","I6";
;
TOLERANCE"1%"
VALUE"100"
PACK_TYPE"0402LF"
WATTAGE"1/16W"
MATERIAL"CHIP"
CDS_LIB"pure_quanta"
PART_NUMBER"CS11002FB07"
LOCATION"R411"
$SEC"1"
CDS_SEC"1";
"A"
$PN"1"16;
"B"
$PN"2"8;
%"Q_RES"
"1","(1625,2925)","0","pure_quanta","I65";
;
PART_NUMBER"CS31002FB08"
VALUE"10K"
MATERIAL"CHIP"
TOLERANCE"1%"
PACK_TYPE"0402LF"
CDS_LIB"pure_quanta"
WATTAGE"1/16W"
$LOCATION"R54"
CDS_LOCATION"R54"
$SEC"1"
CDS_SEC"1";
"B"
$PN"2"25;
"A"
$PN"1"13;
%"Q_RES"
"2","(-1450,2650)","0","pure_quanta","I66";
;
WATTAGE"1/16W"
MATERIAL"EMPTY"
TOLERANCE"1%"
VALUE"1K"
PART_NUMBER"CS21002FB06"
PACK_TYPE"0402LF"
CDS_LIB"pure_quanta"
$LOCATION"R53"
CDS_LOCATION"R53"
$SEC"1"
CDS_SEC"1";
"A"
$PN"1"24;
"B"
$PN"2"11;
%"Q_RES"
"2","(-1450,3350)","0","pure_quanta","I67";
;
WATTAGE"1/16W"
VALUE"4.7K"
TOLERANCE"1%"
PACK_TYPE"0402LF"
PART_NUMBER"CS24702FB06"
MATERIAL"CHIP"
CDS_LIB"pure_quanta"
$LOCATION"R52"
CDS_LOCATION"R52"
$SEC"1"
CDS_SEC"1";
"A"
$PN"1"1;
"B"
$PN"2"24;
%"Q_RES"
"1","(2275,750)","0","pure_quanta","I69";
;
MATERIAL"CHIP"
VALUE"150"
PART_NUMBER"CS11502FB07"
CDS_LIB"pure_quanta"
WATTAGE"1/16W"
TOLERANCE"1%"
PACK_TYPE"0402LF"
LOCATION"R420"
$SEC"1"
CDS_SEC"1";
"B"
$PN"2"23;
"A"
$PN"1"22;
%"UNIVERSAL_GND"
"1","(-1650,25)","0","logical_power","I7";
;
CDS_LIB"logical_power"
HDL_POWER"GND";
"A"8;
%"CONN8_TSW10407FD"
"1","(175,2975)","0","pure_quanta","I71";
;
MATERIAL"EMPTY"
PART_TYPE"THLF"
PART_NUMBER"DFHD08MS225"
VALUE"CONN8_TSW-104-07-F-D"
CDS_LMAN_SYM_OUTLINE"-125,200,125,-200"
NEEDS_NO_SIZE"TRUE"
CDS_LIB"pure_quanta"
LOCATION"J14"
$SEC"1"
CDS_SEC"1";
"2"
$PN"2"15;
"4"
$PN"4"14;
"1"
$PN"1"4;
"3"
$PN"3"28;
"8"
$PN"8"5;
"7"
$PN"7"12;
"6"
$PN"6"13;
"5"
$PN"5"24;
%"Q_RES"
"2","(-1450,500)","0","pure_quanta","I8";
;
VALUE"100"
MATERIAL"CHIP"
PACK_TYPE"0402LF"
TOLERANCE"1%"
WATTAGE"1/16W"
CDS_LIB"pure_quanta"
PART_NUMBER"CS11002FB07"
LOCATION"R412"
$SEC"1"
CDS_SEC"1";
"A"
$PN"1"17;
"B"
$PN"2"8;
%"Q_RES"
"2","(-1800,1175)","0","pure_quanta","I9";
;
WATTAGE"1/16W"
PACK_TYPE"0402LF"
MATERIAL"EMPTY"
TOLERANCE"1%"
VALUE"4.7K"
CDS_LIB"pure_quanta"
SEC_TYPE"0402LF"
PART_NUMBER"CS24702FB06"
LOCATION"R12"
SEC"1";
"A"
$PN"1"3;
"B"
$PN"2"16;
END.
